(kicad_pcb
	(version 20241229)
	(generator "pcbnew")
	(generator_version "9.0")
	(general
		(thickness 1.711)
		(legacy_teardrops no)
	)
	(paper "A4")
	(title_block
		(title "Antmicro Baseboard for Jetson AGX Thor")
		(date "2026-02-18")
		(rev "1.1.0")
		(company "Antmicro Ltd")
		(comment 1 "www.antmicro.com")
		(comment 9 "footprints 337-339 of 1170")
	)
	(layers
		(0 "F.Cu" signal)
		(4 "In1.Cu" signal)
		(6 "In2.Cu" signal)
		(8 "In3.Cu" signal)
		(10 "In4.Cu" jumper)
		(12 "In5.Cu" signal)
		(14 "In6.Cu" signal)
		(16 "In7.Cu" signal)
		(18 "In8.Cu" signal)
		(2 "B.Cu" signal)
		(9 "F.Adhes" user "F.Adhesive")
		(11 "B.Adhes" user "B.Adhesive")
		(13 "F.Paste" user)
		(15 "B.Paste" user)
		(5 "F.SilkS" user "F.Silkscreen")
		(7 "B.SilkS" user "B.Silkscreen")
		(1 "F.Mask" user)
		(3 "B.Mask" user)
		(17 "Dwgs.User" user "User.Drawings")
		(19 "Cmts.User" user "User.Comments")
		(21 "Eco1.User" user "User.Eco1")
		(23 "Eco2.User" user "User.Eco2")
		(25 "Edge.Cuts" user)
		(27 "Margin" user)
		(31 "F.CrtYd" user "F.Courtyard")
		(29 "B.CrtYd" user "B.Courtyard")
		(35 "F.Fab" user)
		(33 "B.Fab" user)
	)
	(footprint "antmicro-footprints:Module_Jetson-Thor-AGX-T5000"
		(layer "F.Cu")
		(at 116.41 103.676 180)
		(descr "Jetson Thor series")
		(tags "Jetson Thor")
		(property "Reference" "A3"
			(at -3.182 -52.1535 0)
			(layer "F.SilkS")
			(hide yes)
			(effects
				(font
					(size 0.7 0.7)
					(thickness 0.15)
				)
				(justify right top)
			)
		)
		(property "Value" "Jetson-Thor-AGX-T5000"
			(at 1.768 54.9945 0)
			(layer "F.Fab")
			(effects
				(font
					(size 0.7 0.7)
					(thickness 0.15)
				)
				(justify right top)
			)
		)
		(property "Datasheet" "https://developer.nvidia.com/embedded/downloads#?tx=$product,jetson_thor"
			(at -166.182 -192.6685 0)
			(layer "F.Fab")
			(hide yes)
			(effects
				(font
					(size 0.7 0.7)
					(thickness 0.15)
				)
				(justify right top)
			)
		)
		(property "Description" "Jetson Thor, System-on-Module, 2560-core NVIDIA Blackwell GPU with 96 fifth-gen Tensor Cores, Multi-Instance GPU with 10TPCs, 14-core Arm Neoverse-V3AE 64-bit CPU, 128 GB LPDDR5X"
			(at -166.182 -192.6685 0)
			(layer "F.Fab")
			(hide yes)
			(effects
				(font
					(size 0.7 0.7)
					(thickness 0.15)
				)
				(justify right top)
			)
		)
		(property "Manufacturer" "Nvidia"
			(at 0 0 180)
			(unlocked yes)
			(layer "F.Fab")
			(hide yes)
			(effects
				(font
					(size 1 1)
					(thickness 0.15)
				)
			)
		)
		(property "MPN" "900-13834-0080-000"
			(at 0 0 180)
			(unlocked yes)
			(layer "F.Fab")
			(hide yes)
			(effects
				(font
					(size 1 1)
					(thickness 0.15)
				)
			)
		)
		(property "Author" "Antmicro"
			(at 0 0 180)
			(unlocked yes)
			(layer "F.Fab")
			(hide yes)
			(effects
				(font
					(size 1 1)
					(thickness 0.15)
				)
			)
		)
		(property "License" "Apache-2.0"
			(at 0 0 180)
			(unlocked yes)
			(layer "F.Fab")
			(hide yes)
			(effects
				(font
					(size 1 1)
					(thickness 0.15)
				)
			)
		)
		(property "Displayed name" "Jetson Thor AGX T5000"
			(at 0 0 180)
			(unlocked yes)
			(layer "F.Fab")
			(hide yes)
			(effects
				(font
					(size 1 1)
					(thickness 0.15)
				)
			)
		)
		(sheetname "/SoM_Power/")
		(sheetfile "som_power.kicad_sch")
		(attr exclude_from_pos_files exclude_from_bom allow_missing_courtyard dnp)
		(fp_circle
			(center 39.5 -46)
			(end 41 -46)
			(stroke
				(width 0.15)
				(type solid)
			)
			(fill no)
			(layer "F.SilkS")
		)
		(fp_text user "License: Apache-2.0"
			(at -43.332 55.1465 0)
			(layer "F.Fab")
			(effects
				(font
					(size 0.7 0.7)
					(thickness 0.15)
				)
				(justify right top)
			)
		)
		(fp_text user "${REFERENCE}"
			(at -43.332 52.7465 0)
			(layer "F.Fab")
			(effects
				(font
					(size 0.7 0.7)
					(thickness 0.15)
				)
				(justify right top)
			)
		)
		(fp_text user "Author: Antmicro"
			(at -43.332 53.9465 0)
			(layer "F.Fab")
			(effects
				(font
					(size 0.7 0.7)
					(thickness 0.15)
				)
				(justify right top)
			)
		)
		(dimension
			(type aligned)
			(layer "Dwgs.User")
			(pts
				(xy 159.91 103.676) (xy 72.91 103.676)
			)
			(height -59.1)
			(format
				(prefix "")
				(suffix "")
				(units 3)
				(units_format 1)
				(precision 2)
			)
			(style
				(thickness 0.1)
				(arrow_length 1.27)
				(text_position_mode 0)
				(arrow_direction outward)
				(extension_height 0.58642)
				(extension_offset 0.5)
				(keep_text_aligned yes)
			)
			(gr_text "87.00 mm"
				(at 116.41 161.626 0)
				(layer "Dwgs.User")
				(effects
					(font
						(size 1 1)
						(thickness 0.15)
					)
				)
			)
		)
		(dimension
			(type aligned)
			(layer "Dwgs.User")
			(pts
				(xy 116.41 53.676) (xy 116.41 153.676)
			)
			(height 54.5)
			(format
				(prefix "")
				(suffix "")
				(units 3)
				(units_format 1)
				(precision 2)
			)
			(style
				(thickness 0.1)
				(arrow_length 1.27)
				(text_position_mode 0)
				(arrow_direction outward)
				(extension_height 0.58642)
				(extension_offset 0.5)
				(keep_text_aligned yes)
			)
			(gr_text "100.00 mm"
				(at 60.76 103.676 90)
				(layer "Dwgs.User")
				(effects
					(font
						(size 1 1)
						(thickness 0.15)
					)
				)
			)
		)
		(dimension
			(type aligned)
			(layer "Dwgs.User")
			(pts
				(xy 155.91 57.676) (xy 159.91 57.676)
			)
			(height -9.5)
			(format
				(prefix "")
				(suffix "")
				(units 3)
				(units_format 1)
				(precision 2)
			)
			(style
				(thickness 0.1)
				(arrow_length 1.27)
				(text_position_mode 2)
				(arrow_direction outward)
				(extension_height 0.58642)
				(extension_offset 0.5)
				(keep_text_aligned yes)
			)
			(gr_text "4.00 mm"
				(at 157.91 46.676 0)
				(layer "Dwgs.User")
				(effects
					(font
						(size 1 1)
						(thickness 0.15)
					)
				)
			)
		)
		(dimension
			(type aligned)
			(layer "Dwgs.User")
			(pts
				(xy 76.91 57.676) (xy 76.91 78.116)
			)
			(height 0)
			(format
				(prefix "")
				(suffix "")
				(units 3)
				(units_format 1)
				(precision 2)
			)
			(style
				(thickness 0.1)
				(arrow_length 1.27)
				(text_position_mode 0)
				(arrow_direction outward)
				(extension_height 0.58642)
				(extension_offset 0.5)
				(keep_text_aligned yes)
			)
			(gr_text "20.44 mm"
				(at 75.76 67.896 90)
				(layer "Dwgs.User")
				(effects
					(font
						(size 1 1)
						(thickness 0.15)
					)
				)
			)
		)
		(dimension
			(type aligned)
			(layer "Dwgs.User")
			(pts
				(xy 155.91 57.676) (xy 155.91 53.676)
			)
			(height 7.5)
			(format
				(prefix "")
				(suffix "")
				(units 3)
				(units_format 1)
				(precision 2)
			)
			(style
				(thickness 0.1)
				(arrow_length 1.27)
				(text_position_mode 2)
				(arrow_direction outward)
				(extension_height 0.58642)
				(extension_offset 0.5)
				(keep_text_aligned yes)
			)
			(gr_text "4.00 mm"
				(at 164.909999 55.676 90)
				(layer "Dwgs.User")
				(effects
					(font
						(size 1 1)
						(thickness 0.15)
					)
				)
			)
		)
		(dimension
			(type aligned)
			(layer "Dwgs.User")
			(pts
				(xy 148.759999 67.116) (xy 148.76 87.216)
			)
			(height -3)
			(format
				(prefix "")
				(suffix "")
				(units 3)
				(units_format 1)
				(precision 2)
			)
			(style
				(thickness 0.1)
				(arrow_length 1.27)
				(text_position_mode 0)
				(arrow_direction outward)
				(extension_height 0.58642)
				(extension_offset 0.5)
				(keep_text_aligned yes)
			)
			(gr_text "20.10 mm"
				(at 152.91 77.166 270.0000057)
				(layer "Dwgs.User")
				(effects
					(font
						(size 1 1)
						(thickness 0.15)
					)
				)
			)
		)
		(dimension
			(type aligned)
			(layer "Dwgs.User")
			(pts
				(xy 148.76 87.216) (xy 84.06 87.216)
			)
			(height -3.96)
			(format
				(prefix "")
				(suffix "")
				(units 3)
				(units_format 1)
				(precision 2)
			)
			(style
				(thickness 0.1)
				(arrow_length 1.27)
				(text_position_mode 2)
				(arrow_direction outward)
				(extension_height 0.58642)
				(extension_offset 0.5)
				(keep_text_aligned yes)
			)
			(gr_text "64.70 mm"
				(at 120.91 92.676 0)
				(layer "Dwgs.User")
				(effects
					(font
						(size 1 1)
						(thickness 0.15)
					)
				)
			)
		)
		(dimension
			(type radial)
			(layer "Dwgs.User")
			(pts
				(xy 74.91 151.676) (xy 73.495786 153.090214)
			)
			(leader_length 6.45934)
			(format
				(prefix "4x R ")
				(suffix "")
				(units 3)
				(units_format 1)
				(precision 2)
			)
			(style
				(thickness 0.1)
				(arrow_length 1.27)
				(text_position_mode 0)
				(extension_offset 0.5)
				(keep_text_aligned yes)
			)
			(gr_text "4x R 2.00 mm"
				(at 59.64 157.657657 0)
				(layer "Dwgs.User")
				(effects
					(font
						(size 1 1)
						(thickness 0.15)
					)
				)
			)
		)
		(dimension
			(type radial)
			(layer "Dwgs.User")
			(pts
				(xy 76.91 57.676) (xy 75.16 57.676)
			)
			(leader_length 5.251023)
			(format
				(prefix "4x ∅")
				(suffix "")
				(units 3)
				(units_format 1)
				(precision 4)
				(override_value "3.50±0.20")
			)
			(style
				(thickness 0.1)
				(arrow_length 1.27)
				(text_position_mode 0)
				(extension_offset 0.5)
				(keep_text_aligned yes)
			)
			(gr_text "4x ∅3.50±0.20 mm"
				(at 59.292206 47.059229 -45)
				(layer "Dwgs.User")
				(effects
					(font
						(size 1 1)
						(thickness 0.15)
					)
				)
			)
		)
	)
	(footprint "antmicro-footprints:R_0402_1005Metric"
		(layer "F.Cu")
		(at 198.9 98.82 -90)
		(descr "Resistor SMD 0402")
		(tags "resistor SMD 0402")
		(property "Reference" "R100"
			(at -0.72 3.5 90)
			(layer "F.SilkS")
			(effects
				(font
					(size 0.7 0.7)
					(thickness 0.15)
				)
				(justify right top)
			)
		)
		(property "Value" "R_0R_0402"
			(at -1.011843 1.772047 90)
			(layer "F.Fab")
			(effects
				(font
					(size 0.7 0.7)
					(thickness 0.15)
				)
				(justify right top)
			)
		)
		(property "Datasheet" "https://industrial.panasonic.com/cdbs/www-data/pdf/RDA0000/AOA0000C301.pdf"
			(at 0 0 90)
			(layer "F.Fab")
			(hide yes)
			(effects
				(font
					(size 1.27 1.27)
					(thickness 0.15)
				)
			)
		)
		(property "Description" "SMD Chip Resistor, Jumper, 0 ohm, 100 mW, 0402 [1005 Metric], Thick Film, General Purpose"
			(at 0 0 90)
			(layer "F.Fab")
			(hide yes)
			(effects
				(font
					(size 1.27 1.27)
					(thickness 0.15)
				)
			)
		)
		(property "MPN" "ERJ2GE0R00X"
			(at 0 0 270)
			(unlocked yes)
			(layer "F.Fab")
			(hide yes)
			(effects
				(font
					(size 1 1)
					(thickness 0.15)
				)
			)
		)
		(property "Manufacturer" "Panasonic"
			(at 0 0 270)
			(unlocked yes)
			(layer "F.Fab")
			(hide yes)
			(effects
				(font
					(size 1 1)
					(thickness 0.15)
				)
			)
		)
		(property "License" "Apache-2.0"
			(at 0 0 270)
			(unlocked yes)
			(layer "F.Fab")
			(hide yes)
			(effects
				(font
					(size 1 1)
					(thickness 0.15)
				)
			)
		)
		(property "Author" "Antmicro"
			(at 0 0 270)
			(unlocked yes)
			(layer "F.Fab")
			(hide yes)
			(effects
				(font
					(size 1 1)
					(thickness 0.15)
				)
			)
		)
		(property "Val" "0R"
			(at 0 0 270)
			(unlocked yes)
			(layer "F.Fab")
			(hide yes)
			(effects
				(font
					(size 1 1)
					(thickness 0.15)
				)
			)
		)
		(property "Tolerance" "~"
			(at 0 0 270)
			(unlocked yes)
			(layer "F.Fab")
			(hide yes)
			(effects
				(font
					(size 1 1)
					(thickness 0.15)
				)
			)
		)
		(property "Current" "1A"
			(at 0 0 270)
			(unlocked yes)
			(layer "F.Fab")
			(hide yes)
			(effects
				(font
					(size 1 1)
					(thickness 0.15)
				)
			)
		)
		(sheetname "/USB Debug, PD/")
		(sheetfile "usb_debug_pd.kicad_sch")
		(attr smd exclude_from_pos_files exclude_from_bom dnp)
		(fp_rect
			(start -0.925 -0.47)
			(end 0.925 0.47)
			(stroke
				(width 0.05)
				(type default)
			)
			(fill no)
			(layer "F.CrtYd")
		)
		(fp_rect
			(start -0.5 -0.25)
			(end 0.5 0.25)
			(stroke
				(width 0.15)
				(type solid)
			)
			(fill no)
			(layer "F.Fab")
		)
		(fp_text user "${REFERENCE}"
			(at -0.95 3.168 90)
			(layer "F.Fab")
			(effects
				(font
					(size 0.7 0.7)
					(thickness 0.15)
				)
				(justify right top)
			)
		)
		(fp_text user "License: Apache-2.0"
			(at -0.95 5.169 90)
			(layer "F.Fab")
			(effects
				(font
					(size 0.7 0.7)
					(thickness 0.15)
				)
				(justify right top)
			)
		)
		(fp_text user "Author: Antmicro"
			(at -0.95 4.169 90)
			(layer "F.Fab")
			(effects
				(font
					(size 0.7 0.7)
					(thickness 0.15)
				)
				(justify right top)
			)
		)
		(pad "1" smd roundrect
			(at -0.48 0 270)
			(size 0.59 0.64)
			(layers "F.Cu" "F.Mask" "F.Paste")
			(roundrect_rratio 0.25)
			(net 531 "Net-(D16-A)")
			(pintype "passive")
		)
		(pad "2" smd roundrect
			(at 0.48 0 270)
			(size 0.59 0.64)
			(layers "F.Cu" "F.Mask" "F.Paste")
			(roundrect_rratio 0.25)
			(net 853 "/I2C_{SYS}.SCL")
			(pintype "passive")
		)
	)
	(footprint "antmicro-footprints:L_MPS-MPL-AL5050"
		(layer "F.Cu")
		(at 180.14 148.83 180)
		(property "Reference" "L6"
			(at -3.369468 -1.33 90)
			(layer "F.SilkS")
			(effects
				(font
					(size 0.7 0.7)
					(thickness 0.15)
				)
				(justify right top)
			)
		)
		(property "Value" "L_6u8_6.1A_MPS-MPL-AL5050"
			(at 0.1 4.25 0)
			(layer "F.Fab")
			(effects
				(font
					(size 0.7 0.7)
					(thickness 0.15)
				)
				(justify right top)
			)
		)
		(property "Datasheet" "https://www.monolithicpower.com/en/documentview/productdocument/index/version/2/document_type/Datasheet/lang/en/sku/MPL-AL5050-6R8/document_id/5811/"
			(at 0 0 0)
			(layer "F.Fab")
			(hide yes)
			(effects
				(font
					(size 1.27 1.27)
					(thickness 0.15)
				)
			)
		)
		(property "Description" "Power Inductor (SMT), 6.8 µH, 6.1 A, Shielded, 7.6 A, MPL-AL"
			(at 0 0 0)
			(layer "F.Fab")
			(hide yes)
			(effects
				(font
					(size 1.27 1.27)
					(thickness 0.15)
				)
			)
		)
		(property "Val" "6u8/6.1A"
			(at 0 0 180)
			(unlocked yes)
			(layer "F.Fab")
			(hide yes)
			(effects
				(font
					(size 1 1)
					(thickness 0.15)
				)
			)
		)
		(property "Manufacturer" "Monolithic Power Systems"
			(at 0 0 180)
			(unlocked yes)
			(layer "F.Fab")
			(hide yes)
			(effects
				(font
					(size 1 1)
					(thickness 0.15)
				)
			)
		)
		(property "MPN" "MPL-AL5050-6R8"
			(at 0 0 180)
			(unlocked yes)
			(layer "F.Fab")
			(hide yes)
			(effects
				(font
					(size 1 1)
					(thickness 0.15)
				)
			)
		)
		(property "ISat" "7.6 A"
			(at 0 0 180)
			(unlocked yes)
			(layer "F.Fab")
			(hide yes)
			(effects
				(font
					(size 1 1)
					(thickness 0.15)
				)
			)
		)
		(property "IMax" "6.1 A"
			(at 0 0 180)
			(unlocked yes)
			(layer "F.Fab")
			(hide yes)
			(effects
				(font
					(size 1 1)
					(thickness 0.15)
				)
			)
		)
		(property "Size" "5.5x5.3"
			(at 0 0 180)
			(unlocked yes)
			(layer "F.Fab")
			(hide yes)
			(effects
				(font
					(size 1 1)
					(thickness 0.15)
				)
			)
		)
		(property "Author" "Antmicro"
			(at 0 0 180)
			(unlocked yes)
			(layer "F.Fab")
			(hide yes)
			(effects
				(font
					(size 1 1)
					(thickness 0.15)
				)
			)
		)
		(property "License" "Apache-2.0"
			(at 0 0 180)
			(unlocked yes)
			(layer "F.Fab")
			(hide yes)
			(effects
				(font
					(size 1 1)
					(thickness 0.15)
				)
			)
		)
		(sheetname "/DCDC/")
		(sheetfile "dcdc.kicad_sch")
		(attr smd)
		(fp_rect
			(start -2.75 -2.85)
			(end 2.75 2.85)
			(stroke
				(width 0.15)
				(type solid)
			)
			(fill no)
			(layer "F.SilkS")
		)
		(fp_rect
			(start -2.9 -3)
			(end 2.9 3)
			(stroke
				(width 0.05)
				(type solid)
			)
			(fill no)
			(layer "F.CrtYd")
		)
		(fp_rect
			(start -2.65 -2.75)
			(end 2.65 2.75)
			(stroke
				(width 0.15)
				(type solid)
			)
			(fill no)
			(layer "F.Fab")
		)
		(fp_text user "License: Apache-2.0"
			(at -2.9 8.65 0)
			(layer "F.Fab")
			(effects
				(font
					(size 0.7 0.7)
					(thickness 0.15)
				)
				(justify right top)
			)
		)
		(fp_text user "Author: Antmicro"
			(at -2.9 6.25 0)
			(layer "F.Fab")
			(effects
				(font
					(size 0.7 0.7)
					(thickness 0.15)
				)
				(justify right top)
			)
		)
		(fp_text user "${REFERENCE}"
			(at -2.9 7.45 0)
			(layer "F.Fab")
			(effects
				(font
					(size 0.7 0.7)
					(thickness 0.15)
				)
				(justify right top)
			)
		)
		(pad "1" smd roundrect
			(at -1.625 0 180)
			(size 1.25 4.7)
			(layers "F.Cu" "F.Mask" "F.Paste")
			(roundrect_rratio 0.1)
			(net 1186 "/DCDC/12V_SW")
			(pintype "passive")
		)
		(pad "2" smd roundrect
			(at 1.625 0 180)
			(size 1.25 4.7)
			(layers "F.Cu" "F.Mask" "F.Paste")
			(roundrect_rratio 0.1)
			(net 880 "/DCDC/12V_OUT")
			(pintype "passive")
		)
	)
)
